(kicad_pcb
	(version 20260206)
	(generator "pcbnew")
	(generator_version "10.0")
	(general
		(thickness 1.6)
		(legacy_teardrops no)
	)
	(paper "A4")
	(title_block
		(title "panther-plus-userver — 13130-1b_20150205.brd")
		(comment 1 "Honey Badger (Wiwynn) / footprints 1195-1202 of 1509")
	)
	(layers
		(0 "F.Cu" signal "TOP")
		(4 "In1.Cu" signal "L2")
		(6 "In2.Cu" signal "L3")
		(8 "In3.Cu" signal "L4")
		(10 "In4.Cu" signal "L5")
		(12 "In5.Cu" signal "L6")
		(14 "In6.Cu" signal "L7")
		(16 "In7.Cu" signal "L8")
		(18 "In8.Cu" signal "L9")
		(20 "In9.Cu" signal "L10")
		(22 "In10.Cu" signal "L11")
		(2 "B.Cu" signal "BOTTOM")
		(9 "F.Adhes" user "F.Adhesive")
		(11 "B.Adhes" user "B.Adhesive")
		(13 "F.Paste" user "Package Geometry/Pastemask Top")
		(15 "B.Paste" user "Package Geometry/Pastemask Bottom")
		(5 "F.SilkS" user "Ref Des/Silkscreen Top")
		(7 "B.SilkS" user "Ref Des/Silkscreen Bottom")
		(1 "F.Mask" user "Board Geometry/Soldermask Top")
		(3 "B.Mask" user "Board Geometry/Soldermask Bottom")
		(17 "Dwgs.User" user "User.Drawings")
		(19 "Cmts.User" user "User.Comments")
		(21 "Eco1.User" user "User.Eco1")
		(23 "Eco2.User" user "User.Eco2")
		(25 "Edge.Cuts" user "Board Geometry/Outline")
		(27 "Margin" user)
		(31 "F.CrtYd" user "Package Geometry/Place Bound Top")
		(29 "B.CrtYd" user "Package Geometry/Place Bound Bottom")
		(35 "F.Fab" user "Ref Des/Assembly Top")
		(33 "B.Fab" user "Ref Des/Assembly Bottom")
	)
	(footprint ""
		(layer "B.Cu")
		(at 95.25 -31.385002 -90)
		(property "Reference" "TP47"
			(at 0 0 90)
			(layer "B.SilkS")
			(hide yes)
			(effects
				(font
					(size 1.27 1.27)
				)
				(justify mirror)
			)
		)
		(property "Value" "TPAD24"
			(at 0 -2.9972 270)
			(unlocked yes)
			(layer "B.Fab")
			(hide yes)
			(effects
				(font
					(size 1.016 1.016)
					(thickness 0.1524)
				)
				(justify mirror)
			)
		)
		(property "Device Type" "TPAD24"
			(at 0 -4.5212 270)
			(unlocked yes)
			(layer "B.Fab")
			(hide yes)
			(effects
				(font
					(size 1.016 1.016)
					(thickness 0.1524)
				)
				(justify mirror)
			)
		)
		(duplicate_pad_numbers_are_jumpers no)
		(fp_poly
			(pts
				(arc
					(start 0 -0.3048)
					(mid 0 0.3048)
					(end 0 -0.3048)
				)
			)
			(stroke
				(width 0)
				(type default)
			)
			(fill no)
			(layer "B.CrtYd")
		)
		(fp_poly
			(pts
				(arc
					(start 0 -0.6096)
					(mid 0 0.6096)
					(end 0 -0.6096)
				)
			)
			(stroke
				(width 0)
				(type default)
			)
			(fill no)
			(layer "B.Fab")
		)
		(pad "1" smd circle
			(at 0 0 90)
			(size 0.6096 0.6096)
			(layers "B.Cu" "B.Mask" "B.Paste")
			(net "TP_CPU_RSVD14")
		)
	)
	(footprint ""
		(layer "B.Cu")
		(at 31.496 -53.594)
		(property "Reference" "PR178"
			(at 0 0 0)
			(layer "B.SilkS")
			(hide yes)
			(effects
				(font
					(size 1.27 1.27)
				)
				(justify mirror)
			)
		)
		(property "Value" "0R2J-2-GP"
			(at -1.7907 -1.1176 0)
			(unlocked yes)
			(layer "B.Fab")
			(hide yes)
			(effects
				(font
					(size 1.016 1.016)
					(thickness 0.1524)
				)
				(justify mirror)
			)
		)
		(property "Device Type" "R402H16"
			(at -1.7907 -2.6416 0)
			(unlocked yes)
			(layer "B.Fab")
			(hide yes)
			(effects
				(font
					(size 1.016 1.016)
					(thickness 0.1524)
				)
				(justify mirror)
			)
		)
		(duplicate_pad_numbers_are_jumpers no)
		(fp_rect
			(start 0.381 0.8382)
			(end -0.381 -0.8382)
			(stroke
				(width 0)
				(type default)
			)
			(fill no)
			(layer "B.CrtYd")
		)
		(fp_rect
			(start 0.381 0.8382)
			(end -0.381 -0.8382)
			(stroke
				(width 0)
				(type default)
			)
			(fill no)
			(layer "B.Fab")
		)
		(pad "1" smd custom
			(at 0 -0.4318 180)
			(size 0.127 0.127)
			(layers "B.Cu" "B.Mask" "B.Paste")
			(net "P3V3_STBY")
			(options
				(clearance outline)
				(anchor circle)
			)
			(primitives
				(gr_poly
					(pts
						(arc
							(start -0.2032 0.2794)
							(mid -0.239121 0.264521)
							(end -0.254 0.2286)
						)
						(arc
							(start -0.254 -0.2286)
							(mid -0.239121 -0.264521)
							(end -0.2032 -0.2794)
						)
						(arc
							(start 0.2032 -0.2794)
							(mid 0.239121 -0.264521)
							(end 0.254 -0.2286)
						)
						(arc
							(start 0.254 0.2286)
							(mid 0.239121 0.264521)
							(end 0.2032 0.2794)
						)
					)
					(width 0)
					(fill yes)
				)
			)
		)
		(pad "2" smd custom
			(at 0 0.4318 180)
			(size 0.127 0.127)
			(layers "B.Cu" "B.Mask" "B.Paste")
			(net "P1V5_STBY_BIAS")
			(options
				(clearance outline)
				(anchor circle)
			)
			(primitives
				(gr_poly
					(pts
						(arc
							(start -0.2032 0.2794)
							(mid -0.239121 0.264521)
							(end -0.254 0.2286)
						)
						(arc
							(start -0.254 -0.2286)
							(mid -0.239121 -0.264521)
							(end -0.2032 -0.2794)
						)
						(arc
							(start 0.2032 -0.2794)
							(mid 0.239121 -0.264521)
							(end 0.254 -0.2286)
						)
						(arc
							(start 0.254 0.2286)
							(mid 0.239121 0.264521)
							(end 0.2032 0.2794)
						)
					)
					(width 0)
					(fill yes)
				)
			)
		)
	)
	(footprint ""
		(layer "B.Cu")
		(at 185.039 -14.986 90)
		(property "Reference" "PC207"
			(at 0 0 90)
			(layer "B.SilkS")
			(hide yes)
			(effects
				(font
					(size 1.27 1.27)
				)
				(justify mirror)
			)
		)
		(property "Value" "SC10U6D3V3MX-GP"
			(at 0 -2.8194 90)
			(unlocked yes)
			(layer "B.Fab")
			(hide yes)
			(effects
				(font
					(size 1.016 1.016)
					(thickness 0.1524)
				)
				(justify mirror)
			)
		)
		(property "Device Type" "C603H38"
			(at 0 -4.3434 90)
			(unlocked yes)
			(layer "B.Fab")
			(hide yes)
			(effects
				(font
					(size 1.016 1.016)
					(thickness 0.1524)
				)
				(justify mirror)
			)
		)
		(duplicate_pad_numbers_are_jumpers no)
		(fp_line
			(start 0.4064 0)
			(end -0.4064 0)
			(stroke
				(width 0.2286)
				(type default)
			)
			(layer "B.SilkS")
		)
		(fp_rect
			(start 0.635 1.1811)
			(end -0.635 -1.1811)
			(stroke
				(width 0)
				(type default)
			)
			(fill no)
			(layer "B.CrtYd")
		)
		(fp_rect
			(start 0.635 1.1811)
			(end -0.635 -1.1811)
			(stroke
				(width 0)
				(type default)
			)
			(fill no)
			(layer "B.Fab")
		)
		(pad "1" smd custom
			(at 0 -0.6604 270)
			(size 0.19685 0.19685)
			(layers "B.Cu" "B.Mask" "B.Paste")
			(net "GND")
			(options
				(clearance outline)
				(anchor circle)
			)
			(primitives
				(gr_poly
					(pts
						(arc
							(start 0.508 0.2921)
							(mid 0.478242 0.363942)
							(end 0.4064 0.3937)
						)
						(arc
							(start -0.4064 0.3937)
							(mid -0.478242 0.363942)
							(end -0.508 0.2921)
						)
						(arc
							(start -0.508 -0.2921)
							(mid -0.478242 -0.363942)
							(end -0.4064 -0.3937)
						)
						(arc
							(start 0.4064 -0.3937)
							(mid 0.478242 -0.363942)
							(end 0.508 -0.2921)
						)
					)
					(width 0)
					(fill yes)
				)
			)
		)
		(pad "2" smd custom
			(at 0 0.6604 270)
			(size 0.19685 0.19685)
			(layers "B.Cu" "B.Mask" "B.Paste")
			(net "PV_VTT_DDR_B")
			(options
				(clearance outline)
				(anchor circle)
			)
			(primitives
				(gr_poly
					(pts
						(arc
							(start 0.508 0.2921)
							(mid 0.478242 0.363942)
							(end 0.4064 0.3937)
						)
						(arc
							(start -0.4064 0.3937)
							(mid -0.478242 0.363942)
							(end -0.508 0.2921)
						)
						(arc
							(start -0.508 -0.2921)
							(mid -0.478242 -0.363942)
							(end -0.4064 -0.3937)
						)
						(arc
							(start 0.4064 -0.3937)
							(mid 0.478242 -0.363942)
							(end 0.508 -0.2921)
						)
					)
					(width 0)
					(fill yes)
				)
			)
		)
	)
	(footprint ""
		(layer "B.Cu")
		(at 22.5552 -56.261 180)
		(property "Reference" "PC65"
			(at 0 0 0)
			(layer "B.SilkS")
			(hide yes)
			(effects
				(font
					(size 1.27 1.27)
				)
				(justify mirror)
			)
		)
		(property "Value" "SC1U16V3KX-5GP"
			(at 0.0254 -2.0193 180)
			(unlocked yes)
			(layer "B.Fab")
			(hide yes)
			(effects
				(font
					(size 1.016 1.016)
					(thickness 0.1524)
				)
				(justify mirror)
			)
		)
		(property "Device Type" "C603H36"
			(at 0.0254 -3.5433 180)
			(unlocked yes)
			(layer "B.Fab")
			(hide yes)
			(effects
				(font
					(size 1.016 1.016)
					(thickness 0.1524)
				)
				(justify mirror)
			)
		)
		(duplicate_pad_numbers_are_jumpers no)
		(fp_line
			(start 0.4064 0)
			(end -0.4064 0)
			(stroke
				(width 0.2286)
				(type default)
			)
			(layer "B.SilkS")
		)
		(fp_rect
			(start 0.635 1.1811)
			(end -0.635 -1.1811)
			(stroke
				(width 0)
				(type default)
			)
			(fill no)
			(layer "B.CrtYd")
		)
		(fp_rect
			(start 0.635 1.1811)
			(end -0.635 -1.1811)
			(stroke
				(width 0)
				(type default)
			)
			(fill no)
			(layer "B.Fab")
		)
		(pad "1" smd custom
			(at 0 -0.6604)
			(size 0.19685 0.19685)
			(layers "B.Cu" "B.Mask" "B.Paste")
			(net "VR_PVCCP_PVNN_VDD")
			(options
				(clearance outline)
				(anchor circle)
			)
			(primitives
				(gr_poly
					(pts
						(arc
							(start 0.508 0.2921)
							(mid 0.478242 0.363942)
							(end 0.4064 0.3937)
						)
						(arc
							(start -0.4064 0.3937)
							(mid -0.478242 0.363942)
							(end -0.508 0.2921)
						)
						(arc
							(start -0.508 -0.2921)
							(mid -0.478242 -0.363942)
							(end -0.4064 -0.3937)
						)
						(arc
							(start 0.4064 -0.3937)
							(mid 0.478242 -0.363942)
							(end 0.508 -0.2921)
						)
					)
					(width 0)
					(fill yes)
				)
			)
		)
		(pad "2" smd custom
			(at 0 0.6604)
			(size 0.19685 0.19685)
			(layers "B.Cu" "B.Mask" "B.Paste")
			(net "GND")
			(options
				(clearance outline)
				(anchor circle)
			)
			(primitives
				(gr_poly
					(pts
						(arc
							(start 0.508 0.2921)
							(mid 0.478242 0.363942)
							(end 0.4064 0.3937)
						)
						(arc
							(start -0.4064 0.3937)
							(mid -0.478242 0.363942)
							(end -0.508 0.2921)
						)
						(arc
							(start -0.508 -0.2921)
							(mid -0.478242 -0.363942)
							(end -0.4064 -0.3937)
						)
						(arc
							(start 0.4064 -0.3937)
							(mid 0.478242 -0.363942)
							(end 0.508 -0.2921)
						)
					)
					(width 0)
					(fill yes)
				)
			)
		)
	)
	(footprint ""
		(layer "B.Cu")
		(at 110.236 -13.335)
		(property "Reference" "R467"
			(at 0 0 0)
			(layer "B.SilkS")
			(hide yes)
			(effects
				(font
					(size 1.27 1.27)
				)
				(justify mirror)
			)
		)
		(property "Value" "4K7R2F-GP"
			(at -1.7907 -1.1176 0)
			(unlocked yes)
			(layer "B.Fab")
			(hide yes)
			(effects
				(font
					(size 1.016 1.016)
					(thickness 0.1524)
				)
				(justify mirror)
			)
		)
		(property "Device Type" "R402H16"
			(at -1.7907 -2.6416 0)
			(unlocked yes)
			(layer "B.Fab")
			(hide yes)
			(effects
				(font
					(size 1.016 1.016)
					(thickness 0.1524)
				)
				(justify mirror)
			)
		)
		(duplicate_pad_numbers_are_jumpers no)
		(fp_rect
			(start 0.381 0.8382)
			(end -0.381 -0.8382)
			(stroke
				(width 0)
				(type default)
			)
			(fill no)
			(layer "B.CrtYd")
		)
		(fp_rect
			(start 0.381 0.8382)
			(end -0.381 -0.8382)
			(stroke
				(width 0)
				(type default)
			)
			(fill no)
			(layer "B.Fab")
		)
		(pad "1" smd custom
			(at 0 -0.4318 180)
			(size 0.127 0.127)
			(layers "B.Cu" "B.Mask" "B.Paste")
			(net "P3V3")
			(options
				(clearance outline)
				(anchor circle)
			)
			(primitives
				(gr_poly
					(pts
						(arc
							(start -0.2032 0.2794)
							(mid -0.239121 0.264521)
							(end -0.254 0.2286)
						)
						(arc
							(start -0.254 -0.2286)
							(mid -0.239121 -0.264521)
							(end -0.2032 -0.2794)
						)
						(arc
							(start 0.2032 -0.2794)
							(mid 0.239121 -0.264521)
							(end 0.254 -0.2286)
						)
						(arc
							(start 0.254 0.2286)
							(mid 0.239121 0.264521)
							(end 0.2032 0.2794)
						)
					)
					(width 0)
					(fill yes)
				)
			)
		)
		(pad "2" smd custom
			(at 0 0.4318 180)
			(size 0.127 0.127)
			(layers "B.Cu" "B.Mask" "B.Paste")
			(net "IRQ_CPU_SERIAL")
			(options
				(clearance outline)
				(anchor circle)
			)
			(primitives
				(gr_poly
					(pts
						(arc
							(start -0.2032 0.2794)
							(mid -0.239121 0.264521)
							(end -0.254 0.2286)
						)
						(arc
							(start -0.254 -0.2286)
							(mid -0.239121 -0.264521)
							(end -0.2032 -0.2794)
						)
						(arc
							(start 0.2032 -0.2794)
							(mid 0.239121 -0.264521)
							(end 0.254 -0.2286)
						)
						(arc
							(start 0.254 0.2286)
							(mid 0.239121 0.264521)
							(end 0.2032 0.2794)
						)
					)
					(width 0)
					(fill yes)
				)
			)
		)
	)
	(footprint ""
		(layer "B.Cu")
		(at 22.479 -12.7)
		(property "Reference" "C284"
			(at 0 0 0)
			(layer "B.SilkS")
			(hide yes)
			(effects
				(font
					(size 1.27 1.27)
				)
				(justify mirror)
			)
		)
		(property "Value" "SCD1U16V2KX-3GP"
			(at -1.1811 -2.7051 0)
			(unlocked yes)
			(layer "B.Fab")
			(hide yes)
			(effects
				(font
					(size 1.016 1.016)
					(thickness 0.1524)
				)
				(justify mirror)
			)
		)
		(property "Device Type" "C402H22"
			(at -1.1811 -4.2291 0)
			(unlocked yes)
			(layer "B.Fab")
			(hide yes)
			(effects
				(font
					(size 1.016 1.016)
					(thickness 0.1524)
				)
				(justify mirror)
			)
		)
		(duplicate_pad_numbers_are_jumpers no)
		(fp_rect
			(start 0.381 0.7366)
			(end -0.381 -0.7366)
			(stroke
				(width 0)
				(type default)
			)
			(fill no)
			(layer "B.CrtYd")
		)
		(fp_rect
			(start 0.381 0.7366)
			(end -0.381 -0.7366)
			(stroke
				(width 0)
				(type default)
			)
			(fill no)
			(layer "B.Fab")
		)
		(pad "1" smd custom
			(at 0 -0.4572 180)
			(size 0.1143 0.1143)
			(layers "B.Cu" "B.Mask" "B.Paste")
			(net "P2E_CPU_ETH10G_C_TX_DP10")
			(options
				(clearance outline)
				(anchor circle)
			)
			(primitives
				(gr_poly
					(pts
						(arc
							(start -0.254 0.1778)
							(mid -0.239121 0.213721)
							(end -0.2032 0.2286)
						)
						(arc
							(start 0.2032 0.2286)
							(mid 0.239121 0.213721)
							(end 0.254 0.1778)
						)
						(arc
							(start 0.254 -0.1778)
							(mid 0.239121 -0.213721)
							(end 0.2032 -0.2286)
						)
						(arc
							(start -0.2032 -0.2286)
							(mid -0.239121 -0.213721)
							(end -0.254 -0.1778)
						)
					)
					(width 0)
					(fill yes)
				)
			)
		)
		(pad "2" smd custom
			(at 0 0.4572 180)
			(size 0.1143 0.1143)
			(layers "B.Cu" "B.Mask" "B.Paste")
			(net "P2E_CPU_ETH10G_TX_DP10")
			(options
				(clearance outline)
				(anchor circle)
			)
			(primitives
				(gr_poly
					(pts
						(arc
							(start -0.254 0.1778)
							(mid -0.239121 0.213721)
							(end -0.2032 0.2286)
						)
						(arc
							(start 0.2032 0.2286)
							(mid 0.239121 0.213721)
							(end 0.254 0.1778)
						)
						(arc
							(start 0.254 -0.1778)
							(mid 0.239121 -0.213721)
							(end 0.2032 -0.2286)
						)
						(arc
							(start -0.2032 -0.2286)
							(mid -0.239121 -0.213721)
							(end -0.254 -0.1778)
						)
					)
					(width 0)
					(fill yes)
				)
			)
		)
	)
	(footprint ""
		(layer "B.Cu")
		(at 74.041 -28.702 90)
		(property "Reference" "R456"
			(at 0 0 90)
			(layer "B.SilkS")
			(hide yes)
			(effects
				(font
					(size 1.27 1.27)
				)
				(justify mirror)
			)
		)
		(property "Value" "10KR2F-2-GP"
			(at -1.7907 -1.1176 90)
			(unlocked yes)
			(layer "B.Fab")
			(hide yes)
			(effects
				(font
					(size 1.016 1.016)
					(thickness 0.1524)
				)
				(justify mirror)
			)
		)
		(property "Device Type" "R402H16"
			(at -1.7907 -2.6416 90)
			(unlocked yes)
			(layer "B.Fab")
			(hide yes)
			(effects
				(font
					(size 1.016 1.016)
					(thickness 0.1524)
				)
				(justify mirror)
			)
		)
		(duplicate_pad_numbers_are_jumpers no)
		(fp_rect
			(start 0.381 0.8382)
			(end -0.381 -0.8382)
			(stroke
				(width 0)
				(type default)
			)
			(fill no)
			(layer "B.CrtYd")
		)
		(fp_rect
			(start 0.381 0.8382)
			(end -0.381 -0.8382)
			(stroke
				(width 0)
				(type default)
			)
			(fill no)
			(layer "B.Fab")
		)
		(pad "1" smd custom
			(at 0 -0.4318 270)
			(size 0.127 0.127)
			(layers "B.Cu" "B.Mask" "B.Paste")
			(net "P3V3_CPU")
			(options
				(clearance outline)
				(anchor circle)
			)
			(primitives
				(gr_poly
					(pts
						(arc
							(start -0.2032 0.2794)
							(mid -0.239121 0.264521)
							(end -0.254 0.2286)
						)
						(arc
							(start -0.254 -0.2286)
							(mid -0.239121 -0.264521)
							(end -0.2032 -0.2794)
						)
						(arc
							(start 0.2032 -0.2794)
							(mid 0.239121 -0.264521)
							(end 0.254 -0.2286)
						)
						(arc
							(start 0.254 0.2286)
							(mid 0.239121 0.264521)
							(end 0.2032 0.2794)
						)
					)
					(width 0)
					(fill yes)
				)
			)
		)
		(pad "2" smd custom
			(at 0 0.4318 270)
			(size 0.127 0.127)
			(layers "B.Cu" "B.Mask" "B.Paste")
			(net "REV_CPU_FPGA_IO1")
			(options
				(clearance outline)
				(anchor circle)
			)
			(primitives
				(gr_poly
					(pts
						(arc
							(start -0.2032 0.2794)
							(mid -0.239121 0.264521)
							(end -0.254 0.2286)
						)
						(arc
							(start -0.254 -0.2286)
							(mid -0.239121 -0.264521)
							(end -0.2032 -0.2794)
						)
						(arc
							(start 0.2032 -0.2794)
							(mid 0.239121 -0.264521)
							(end 0.254 -0.2286)
						)
						(arc
							(start 0.254 0.2286)
							(mid 0.239121 0.264521)
							(end 0.2032 0.2794)
						)
					)
					(width 0)
					(fill yes)
				)
			)
		)
	)
	(footprint ""
		(layer "B.Cu")
		(at 98.933 -53.467 -90)
		(property "Reference" "C125"
			(at 0 0 90)
			(layer "B.SilkS")
			(hide yes)
			(effects
				(font
					(size 1.27 1.27)
				)
				(justify mirror)
			)
		)
		(property "Value" "SCD1U16V2KX-L-GP"
			(at -1.1811 -2.7051 270)
			(unlocked yes)
			(layer "B.Fab")
			(hide yes)
			(effects
				(font
					(size 1.016 1.016)
					(thickness 0.1524)
				)
				(justify mirror)
			)
		)
		(property "Device Type" "C402H22"
			(at -1.1811 -4.2291 270)
			(unlocked yes)
			(layer "B.Fab")
			(hide yes)
			(effects
				(font
					(size 1.016 1.016)
					(thickness 0.1524)
				)
				(justify mirror)
			)
		)
		(duplicate_pad_numbers_are_jumpers no)
		(fp_rect
			(start 0.381 0.7366)
			(end -0.381 -0.7366)
			(stroke
				(width 0)
				(type default)
			)
			(fill no)
			(layer "B.CrtYd")
		)
		(fp_rect
			(start 0.381 0.7366)
			(end -0.381 -0.7366)
			(stroke
				(width 0)
				(type default)
			)
			(fill no)
			(layer "B.Fab")
		)
		(pad "1" smd custom
			(at 0 -0.4572 90)
			(size 0.1143 0.1143)
			(layers "B.Cu" "B.Mask" "B.Paste")
			(net "M_A_VREF")
			(options
				(clearance outline)
				(anchor circle)
			)
			(primitives
				(gr_poly
					(pts
						(arc
							(start -0.254 0.1778)
							(mid -0.239121 0.213721)
							(end -0.2032 0.2286)
						)
						(arc
							(start 0.2032 0.2286)
							(mid 0.239121 0.213721)
							(end 0.254 0.1778)
						)
						(arc
							(start 0.254 -0.1778)
							(mid 0.239121 -0.213721)
							(end 0.2032 -0.2286)
						)
						(arc
							(start -0.2032 -0.2286)
							(mid -0.239121 -0.213721)
							(end -0.254 -0.1778)
						)
					)
					(width 0)
					(fill yes)
				)
			)
		)
		(pad "2" smd custom
			(at 0 0.4572 90)
			(size 0.1143 0.1143)
			(layers "B.Cu" "B.Mask" "B.Paste")
			(net "GND")
			(options
				(clearance outline)
				(anchor circle)
			)
			(primitives
				(gr_poly
					(pts
						(arc
							(start -0.254 0.1778)
							(mid -0.239121 0.213721)
							(end -0.2032 0.2286)
						)
						(arc
							(start 0.2032 0.2286)
							(mid 0.239121 0.213721)
							(end 0.254 0.1778)
						)
						(arc
							(start 0.254 -0.1778)
							(mid 0.239121 -0.213721)
							(end 0.2032 -0.2286)
						)
						(arc
							(start -0.2032 -0.2286)
							(mid -0.239121 -0.213721)
							(end -0.254 -0.1778)
						)
					)
					(width 0)
					(fill yes)
				)
			)
		)
	)
)
